(kicad_pcb
	(version 20260206)
	(generator "pcbnew")
	(generator_version "10.0")
	(general
		(thickness 1.6)
		(legacy_teardrops no)
	)
	(paper "A4")
	(title_block
		(title "peb — Lightning_PEB_BRD.brd")
		(comment 1 "Lightning (Wiwynn / Facebook NVMe JBOF) / footprints 1086-1093 of 2563")
	)
	(layers
		(0 "F.Cu" signal "TOP")
		(4 "In1.Cu" signal "L2GND")
		(6 "In2.Cu" signal "L3")
		(8 "In3.Cu" signal "L4VCC")
		(10 "In4.Cu" signal "L5VCC")
		(12 "In5.Cu" signal "L6")
		(14 "In6.Cu" signal "L7GND")
		(2 "B.Cu" signal "BOTTOM")
		(9 "F.Adhes" user "F.Adhesive")
		(11 "B.Adhes" user "B.Adhesive")
		(13 "F.Paste" user "Package Geometry/Pastemask Top")
		(15 "B.Paste" user "Package Geometry/Pastemask Bottom")
		(5 "F.SilkS" user "Ref Des/Silkscreen Top")
		(7 "B.SilkS" user "Ref Des/Silkscreen Bottom")
		(1 "F.Mask" user "Board Geometry/Soldermask Top")
		(3 "B.Mask" user "Board Geometry/Soldermask Bottom")
		(17 "Dwgs.User" user "User.Drawings")
		(19 "Cmts.User" user "User.Comments")
		(21 "Eco1.User" user "User.Eco1")
		(23 "Eco2.User" user "User.Eco2")
		(25 "Edge.Cuts" user "Board Geometry/Outline")
		(27 "Margin" user)
		(31 "F.CrtYd" user "Package Geometry/Place Bound Top")
		(29 "B.CrtYd" user "Package Geometry/Place Bound Bottom")
		(35 "F.Fab" user "Ref Des/Assembly Top")
		(33 "B.Fab" user "Ref Des/Assembly Bottom")
	)
	(footprint ""
		(layer "F.Cu")
		(at 122.557286 -86.116414 -90)
		(property "Reference" "R5201"
			(at 0 0 270)
			(layer "F.SilkS")
			(hide yes)
			(effects
				(font
					(size 1.27 1.27)
				)
			)
		)
		(property "Value" "0R2J-2-GP"
			(at 0.064008 -3.993896 270)
			(unlocked yes)
			(layer "F.Fab")
			(hide yes)
			(effects
				(font
					(size 1.016 1.016)
					(thickness 0.1524)
				)
			)
		)
		(property "Device Type" "R402H16"
			(at 0.064008 -5.517896 270)
			(unlocked yes)
			(layer "F.Fab")
			(hide yes)
			(effects
				(font
					(size 1.016 1.016)
					(thickness 0.1524)
				)
			)
		)
		(duplicate_pad_numbers_are_jumpers no)
		(fp_line
			(start -0.508 -0.9398)
			(end -0.508 0.9398)
			(stroke
				(width 0.1524)
				(type default)
			)
			(layer "F.SilkS")
		)
		(fp_line
			(start 0.508 -0.9398)
			(end -0.508 -0.9398)
			(stroke
				(width 0.1524)
				(type default)
			)
			(layer "F.SilkS")
		)
		(fp_rect
			(start -0.508 0.9398)
			(end 0.508 -0.9398)
			(stroke
				(width 0)
				(type default)
			)
			(fill no)
			(layer "F.CrtYd")
		)
		(fp_rect
			(start -0.508 0.9398)
			(end 0.508 -0.9398)
			(stroke
				(width 0)
				(type default)
			)
			(fill no)
			(layer "F.Fab")
		)
		(pad "1" smd custom
			(at 0 -0.4445 270)
			(size 0.1397 0.1397)
			(layers "F.Cu" "F.Mask" "F.Paste")
			(net "RTC_I2C_SDA")
			(options
				(clearance outline)
				(anchor circle)
			)
			(primitives
				(gr_poly
					(pts
						(arc
							(start -0.1778 -0.2794)
							(mid -0.249642 -0.249642)
							(end -0.2794 -0.1778)
						)
						(arc
							(start -0.2794 0.1778)
							(mid -0.249642 0.249642)
							(end -0.1778 0.2794)
						)
						(arc
							(start 0.1778 0.2794)
							(mid 0.249642 0.249642)
							(end 0.2794 0.1778)
						)
						(arc
							(start 0.2794 -0.1778)
							(mid 0.249642 -0.249642)
							(end 0.1778 -0.2794)
						)
					)
					(width 0)
					(fill yes)
				)
			)
		)
		(pad "2" smd custom
			(at 0 0.4445 270)
			(size 0.1397 0.1397)
			(layers "F.Cu" "F.Mask" "F.Paste")
			(net "BMC_I2C5_D_PEB_SDA")
			(options
				(clearance outline)
				(anchor circle)
			)
			(primitives
				(gr_poly
					(pts
						(arc
							(start -0.1778 -0.2794)
							(mid -0.249642 -0.249642)
							(end -0.2794 -0.1778)
						)
						(arc
							(start -0.2794 0.1778)
							(mid -0.249642 0.249642)
							(end -0.1778 0.2794)
						)
						(arc
							(start 0.1778 0.2794)
							(mid 0.249642 0.249642)
							(end 0.2794 0.1778)
						)
						(arc
							(start 0.2794 -0.1778)
							(mid 0.249642 -0.249642)
							(end 0.1778 -0.2794)
						)
					)
					(width 0)
					(fill yes)
				)
			)
		)
	)
	(footprint ""
		(layer "F.Cu")
		(at 116.2558 -17.0688)
		(property "Reference" "R750"
			(at 0 0 0)
			(layer "F.SilkS")
			(hide yes)
			(effects
				(font
					(size 1.27 1.27)
				)
			)
		)
		(property "Value" "4K7R2F-GP"
			(at 0.064008 -3.993896 0)
			(unlocked yes)
			(layer "F.Fab")
			(hide yes)
			(effects
				(font
					(size 1.016 1.016)
					(thickness 0.1524)
				)
			)
		)
		(property "Device Type" "R402H16"
			(at 0.064008 -5.517896 0)
			(unlocked yes)
			(layer "F.Fab")
			(hide yes)
			(effects
				(font
					(size 1.016 1.016)
					(thickness 0.1524)
				)
			)
		)
		(duplicate_pad_numbers_are_jumpers no)
		(fp_line
			(start -0.508 -0.9398)
			(end -0.508 0.9398)
			(stroke
				(width 0.1524)
				(type default)
			)
			(layer "F.SilkS")
		)
		(fp_line
			(start 0.508 -0.9398)
			(end -0.508 -0.9398)
			(stroke
				(width 0.1524)
				(type default)
			)
			(layer "F.SilkS")
		)
		(fp_rect
			(start -0.508 0.9398)
			(end 0.508 -0.9398)
			(stroke
				(width 0)
				(type default)
			)
			(fill no)
			(layer "F.CrtYd")
		)
		(fp_rect
			(start -0.508 0.9398)
			(end 0.508 -0.9398)
			(stroke
				(width 0)
				(type default)
			)
			(fill no)
			(layer "F.Fab")
		)
		(pad "1" smd custom
			(at 0 -0.4445)
			(size 0.1397 0.1397)
			(layers "F.Cu" "F.Mask" "F.Paste")
			(net "U54_A0")
			(options
				(clearance outline)
				(anchor circle)
			)
			(primitives
				(gr_poly
					(pts
						(arc
							(start -0.1778 -0.2794)
							(mid -0.249642 -0.249642)
							(end -0.2794 -0.1778)
						)
						(arc
							(start -0.2794 0.1778)
							(mid -0.249642 0.249642)
							(end -0.1778 0.2794)
						)
						(arc
							(start 0.1778 0.2794)
							(mid 0.249642 0.249642)
							(end 0.2794 0.1778)
						)
						(arc
							(start 0.2794 -0.1778)
							(mid 0.249642 -0.249642)
							(end 0.1778 -0.2794)
						)
					)
					(width 0)
					(fill yes)
				)
			)
		)
		(pad "2" smd custom
			(at 0 0.4445)
			(size 0.1397 0.1397)
			(layers "F.Cu" "F.Mask" "F.Paste")
			(net "P3V3_STBY")
			(options
				(clearance outline)
				(anchor circle)
			)
			(primitives
				(gr_poly
					(pts
						(arc
							(start -0.1778 -0.2794)
							(mid -0.249642 -0.249642)
							(end -0.2794 -0.1778)
						)
						(arc
							(start -0.2794 0.1778)
							(mid -0.249642 0.249642)
							(end -0.1778 0.2794)
						)
						(arc
							(start 0.1778 0.2794)
							(mid 0.249642 0.249642)
							(end 0.2794 0.1778)
						)
						(arc
							(start 0.2794 -0.1778)
							(mid 0.249642 -0.249642)
							(end 0.1778 -0.2794)
						)
					)
					(width 0)
					(fill yes)
				)
			)
		)
	)
	(footprint ""
		(layer "F.Cu")
		(at 259.299202 -4.419092 90)
		(property "Reference" "SC1302"
			(at 0 0 90)
			(layer "F.SilkS")
			(hide yes)
			(effects
				(font
					(size 1.27 1.27)
				)
			)
		)
		(property "Value" "SCD1U16V2KX-3GP"
			(at 1.1811 -2.7051 90)
			(unlocked yes)
			(layer "F.Fab")
			(hide yes)
			(effects
				(font
					(size 1.016 1.016)
					(thickness 0.1524)
				)
			)
		)
		(property "Device Type" "C402H22"
			(at 1.1811 -4.2291 90)
			(unlocked yes)
			(layer "F.Fab")
			(hide yes)
			(effects
				(font
					(size 1.016 1.016)
					(thickness 0.1524)
				)
			)
		)
		(duplicate_pad_numbers_are_jumpers no)
		(fp_rect
			(start -0.4318 0.9525)
			(end 0.4318 -0.9525)
			(stroke
				(width 0)
				(type default)
			)
			(fill no)
			(layer "F.CrtYd")
		)
		(fp_rect
			(start -0.4318 0.9525)
			(end 0.4318 -0.9525)
			(stroke
				(width 0)
				(type default)
			)
			(fill no)
			(layer "F.Fab")
		)
		(pad "1" smd custom
			(at 0 -0.4445 90)
			(size 0.1524 0.1524)
			(layers "F.Cu" "F.Mask" "F.Paste")
			(net "P3V3_STBY")
			(options
				(clearance outline)
				(anchor circle)
			)
			(primitives
				(gr_poly
					(pts
						(arc
							(start 0.3048 -0.2032)
							(mid 0.275042 -0.275042)
							(end 0.2032 -0.3048)
						)
						(arc
							(start -0.2032 -0.3048)
							(mid -0.275042 -0.275042)
							(end -0.3048 -0.2032)
						)
						(arc
							(start -0.3048 0.2032)
							(mid -0.275042 0.275042)
							(end -0.2032 0.3048)
						)
						(arc
							(start 0.2032 0.3048)
							(mid 0.275042 0.275042)
							(end 0.3048 0.2032)
						)
					)
					(width 0)
					(fill yes)
				)
			)
		)
		(pad "2" smd custom
			(at 0 0.4445 90)
			(size 0.1524 0.1524)
			(layers "F.Cu" "F.Mask" "F.Paste")
			(net "GND")
			(options
				(clearance outline)
				(anchor circle)
			)
			(primitives
				(gr_poly
					(pts
						(arc
							(start 0.3048 -0.2032)
							(mid 0.275042 -0.275042)
							(end 0.2032 -0.3048)
						)
						(arc
							(start -0.2032 -0.3048)
							(mid -0.275042 -0.275042)
							(end -0.3048 -0.2032)
						)
						(arc
							(start -0.3048 0.2032)
							(mid -0.275042 0.275042)
							(end -0.2032 0.3048)
						)
						(arc
							(start 0.2032 0.3048)
							(mid 0.275042 0.275042)
							(end 0.3048 0.2032)
						)
					)
					(width 0)
					(fill yes)
				)
			)
		)
	)
	(footprint ""
		(layer "F.Cu")
		(at 27.1526 -184.4802 180)
		(property "Reference" "R468"
			(at 0 0 180)
			(layer "F.SilkS")
			(hide yes)
			(effects
				(font
					(size 1.27 1.27)
				)
			)
		)
		(property "Value" "2KR2F-3-GP"
			(at 0.064008 -3.993896 180)
			(unlocked yes)
			(layer "F.Fab")
			(hide yes)
			(effects
				(font
					(size 1.016 1.016)
					(thickness 0.1524)
				)
			)
		)
		(property "Device Type" "R402H16"
			(at 0.064008 -5.517896 180)
			(unlocked yes)
			(layer "F.Fab")
			(hide yes)
			(effects
				(font
					(size 1.016 1.016)
					(thickness 0.1524)
				)
			)
		)
		(duplicate_pad_numbers_are_jumpers no)
		(fp_line
			(start 0.508 -0.9398)
			(end -0.508 -0.9398)
			(stroke
				(width 0.1524)
				(type default)
			)
			(layer "F.SilkS")
		)
		(fp_line
			(start -0.508 -0.9398)
			(end -0.508 0.9398)
			(stroke
				(width 0.1524)
				(type default)
			)
			(layer "F.SilkS")
		)
		(fp_rect
			(start -0.508 0.9398)
			(end 0.508 -0.9398)
			(stroke
				(width 0)
				(type default)
			)
			(fill no)
			(layer "F.CrtYd")
		)
		(fp_rect
			(start -0.508 0.9398)
			(end 0.508 -0.9398)
			(stroke
				(width 0)
				(type default)
			)
			(fill no)
			(layer "F.Fab")
		)
		(pad "1" smd custom
			(at 0 -0.4445 180)
			(size 0.1397 0.1397)
			(layers "F.Cu" "F.Mask" "F.Paste")
			(net "P3V3_STBY")
			(options
				(clearance outline)
				(anchor circle)
			)
			(primitives
				(gr_poly
					(pts
						(arc
							(start -0.1778 -0.2794)
							(mid -0.249642 -0.249642)
							(end -0.2794 -0.1778)
						)
						(arc
							(start -0.2794 0.1778)
							(mid -0.249642 0.249642)
							(end -0.1778 0.2794)
						)
						(arc
							(start 0.1778 0.2794)
							(mid 0.249642 0.249642)
							(end 0.2794 0.1778)
						)
						(arc
							(start 0.2794 -0.1778)
							(mid 0.249642 -0.249642)
							(end 0.1778 -0.2794)
						)
					)
					(width 0)
					(fill yes)
				)
			)
		)
		(pad "2" smd custom
			(at 0 0.4445 180)
			(size 0.1397 0.1397)
			(layers "F.Cu" "F.Mask" "F.Paste")
			(net "BMC_I2C5_SDA_R")
			(options
				(clearance outline)
				(anchor circle)
			)
			(primitives
				(gr_poly
					(pts
						(arc
							(start -0.1778 -0.2794)
							(mid -0.249642 -0.249642)
							(end -0.2794 -0.1778)
						)
						(arc
							(start -0.2794 0.1778)
							(mid -0.249642 0.249642)
							(end -0.1778 0.2794)
						)
						(arc
							(start 0.1778 0.2794)
							(mid 0.249642 0.249642)
							(end 0.2794 0.1778)
						)
						(arc
							(start 0.2794 -0.1778)
							(mid 0.249642 -0.249642)
							(end 0.1778 -0.2794)
						)
					)
					(width 0)
					(fill yes)
				)
			)
		)
	)
	(footprint ""
		(layer "F.Cu")
		(at 155.829 -90.267282 180)
		(property "Reference" "R78"
			(at 0 0 180)
			(layer "F.SilkS")
			(hide yes)
			(effects
				(font
					(size 1.27 1.27)
				)
			)
		)
		(property "Value" "0R2J-2-GP"
			(at 0.064008 -3.993896 180)
			(unlocked yes)
			(layer "F.Fab")
			(hide yes)
			(effects
				(font
					(size 1.016 1.016)
					(thickness 0.1524)
				)
			)
		)
		(property "Device Type" "R402H16"
			(at 0.064008 -5.517896 180)
			(unlocked yes)
			(layer "F.Fab")
			(hide yes)
			(effects
				(font
					(size 1.016 1.016)
					(thickness 0.1524)
				)
			)
		)
		(duplicate_pad_numbers_are_jumpers no)
		(fp_line
			(start 0.508 -0.9398)
			(end -0.508 -0.9398)
			(stroke
				(width 0.1524)
				(type default)
			)
			(layer "F.SilkS")
		)
		(fp_line
			(start -0.508 -0.9398)
			(end -0.508 0.9398)
			(stroke
				(width 0.1524)
				(type default)
			)
			(layer "F.SilkS")
		)
		(fp_rect
			(start -0.508 0.9398)
			(end 0.508 -0.9398)
			(stroke
				(width 0)
				(type default)
			)
			(fill no)
			(layer "F.CrtYd")
		)
		(fp_rect
			(start -0.508 0.9398)
			(end 0.508 -0.9398)
			(stroke
				(width 0)
				(type default)
			)
			(fill no)
			(layer "F.Fab")
		)
		(pad "1" smd custom
			(at 0 -0.4445 180)
			(size 0.1397 0.1397)
			(layers "F.Cu" "F.Mask" "F.Paste")
			(net "XTAL_X2")
			(options
				(clearance outline)
				(anchor circle)
			)
			(primitives
				(gr_poly
					(pts
						(arc
							(start -0.1778 -0.2794)
							(mid -0.249642 -0.249642)
							(end -0.2794 -0.1778)
						)
						(arc
							(start -0.2794 0.1778)
							(mid -0.249642 0.249642)
							(end -0.1778 0.2794)
						)
						(arc
							(start 0.1778 0.2794)
							(mid 0.249642 0.249642)
							(end 0.2794 0.1778)
						)
						(arc
							(start 0.2794 -0.1778)
							(mid 0.249642 -0.249642)
							(end 0.1778 -0.2794)
						)
					)
					(width 0)
					(fill yes)
				)
			)
		)
		(pad "2" smd custom
			(at 0 0.4445 180)
			(size 0.1397 0.1397)
			(layers "F.Cu" "F.Mask" "F.Paste")
			(net "XTAL_X2_CLKGEN")
			(options
				(clearance outline)
				(anchor circle)
			)
			(primitives
				(gr_poly
					(pts
						(arc
							(start -0.1778 -0.2794)
							(mid -0.249642 -0.249642)
							(end -0.2794 -0.1778)
						)
						(arc
							(start -0.2794 0.1778)
							(mid -0.249642 0.249642)
							(end -0.1778 0.2794)
						)
						(arc
							(start 0.1778 0.2794)
							(mid 0.249642 0.249642)
							(end 0.2794 0.1778)
						)
						(arc
							(start 0.2794 -0.1778)
							(mid 0.249642 -0.249642)
							(end 0.1778 -0.2794)
						)
					)
					(width 0)
					(fill yes)
				)
			)
		)
	)
	(footprint ""
		(layer "F.Cu")
		(at 261.9756 -28.575)
		(property "Reference" "TP291"
			(at 0 0 0)
			(layer "F.SilkS")
			(hide yes)
			(effects
				(font
					(size 1.27 1.27)
				)
			)
		)
		(property "Value" "TPAD28-2-GP"
			(at -0.0127 -1.6637 0)
			(unlocked yes)
			(layer "F.Fab")
			(hide yes)
			(effects
				(font
					(size 1.016 1.016)
					(thickness 0.1524)
				)
			)
		)
		(property "Device Type" "TPAD28"
			(at -0.0127 -3.1877 0)
			(unlocked yes)
			(layer "F.Fab")
			(hide yes)
			(effects
				(font
					(size 1.016 1.016)
					(thickness 0.1524)
				)
			)
		)
		(duplicate_pad_numbers_are_jumpers no)
		(fp_poly
			(pts
				(arc
					(start 0.3556 0)
					(mid -0.3556 0)
					(end 0.3556 0)
				)
			)
			(stroke
				(width 0)
				(type default)
			)
			(fill no)
			(layer "F.CrtYd")
		)
		(fp_poly
			(pts
				(arc
					(start 0.6096 0)
					(mid -0.6096 0)
					(end 0.6096 0)
				)
			)
			(stroke
				(width 0)
				(type default)
			)
			(fill no)
			(layer "F.Fab")
		)
		(pad "1" smd circle
			(at 0 0)
			(size 0.7112 0.7112)
			(layers "F.Cu" "F.Mask" "F.Paste")
			(net "TWI_SRST#6")
		)
	)
	(footprint ""
		(layer "F.Cu")
		(at 332.39202 -212.420454 180)
		(property "Reference" "C60"
			(at 0 0 180)
			(layer "F.SilkS")
			(hide yes)
			(effects
				(font
					(size 1.27 1.27)
				)
			)
		)
		(property "Value" "SCD22U10V2KX-1GP"
			(at 1.1811 -2.7051 180)
			(unlocked yes)
			(layer "F.Fab")
			(hide yes)
			(effects
				(font
					(size 1.016 1.016)
					(thickness 0.1524)
				)
			)
		)
		(property "Device Type" "C402H22"
			(at 1.1811 -4.2291 180)
			(unlocked yes)
			(layer "F.Fab")
			(hide yes)
			(effects
				(font
					(size 1.016 1.016)
					(thickness 0.1524)
				)
			)
		)
		(duplicate_pad_numbers_are_jumpers no)
		(fp_rect
			(start -0.4318 0.9525)
			(end 0.4318 -0.9525)
			(stroke
				(width 0)
				(type default)
			)
			(fill no)
			(layer "F.CrtYd")
		)
		(fp_rect
			(start -0.4318 0.9525)
			(end 0.4318 -0.9525)
			(stroke
				(width 0)
				(type default)
			)
			(fill no)
			(layer "F.Fab")
		)
		(pad "1" smd custom
			(at 0 -0.4445 180)
			(size 0.1524 0.1524)
			(layers "F.Cu" "F.Mask" "F.Paste")
			(net "PCIE_TX_CAP_P19")
			(options
				(clearance outline)
				(anchor circle)
			)
			(primitives
				(gr_poly
					(pts
						(arc
							(start 0.3048 -0.2032)
							(mid 0.275042 -0.275042)
							(end 0.2032 -0.3048)
						)
						(arc
							(start -0.2032 -0.3048)
							(mid -0.275042 -0.275042)
							(end -0.3048 -0.2032)
						)
						(arc
							(start -0.3048 0.2032)
							(mid -0.275042 0.275042)
							(end -0.2032 0.3048)
						)
						(arc
							(start 0.2032 0.3048)
							(mid 0.275042 0.275042)
							(end 0.3048 0.2032)
						)
					)
					(width 0)
					(fill yes)
				)
			)
		)
		(pad "2" smd custom
			(at 0 0.4445 180)
			(size 0.1524 0.1524)
			(layers "F.Cu" "F.Mask" "F.Paste")
			(net "PCIE_TX_P19")
			(options
				(clearance outline)
				(anchor circle)
			)
			(primitives
				(gr_poly
					(pts
						(arc
							(start 0.3048 -0.2032)
							(mid 0.275042 -0.275042)
							(end 0.2032 -0.3048)
						)
						(arc
							(start -0.2032 -0.3048)
							(mid -0.275042 -0.275042)
							(end -0.3048 -0.2032)
						)
						(arc
							(start -0.3048 0.2032)
							(mid -0.275042 0.275042)
							(end -0.2032 0.3048)
						)
						(arc
							(start 0.2032 0.3048)
							(mid 0.275042 0.275042)
							(end 0.3048 0.2032)
						)
					)
					(width 0)
					(fill yes)
				)
			)
		)
	)
	(footprint ""
		(layer "F.Cu")
		(at 23.495 -119.761)
		(property "Reference" "R234"
			(at 0 0 0)
			(layer "F.SilkS")
			(hide yes)
			(effects
				(font
					(size 1.27 1.27)
				)
			)
		)
		(property "Value" "100KR2F-L1-GP"
			(at 0.064008 -3.993896 0)
			(unlocked yes)
			(layer "F.Fab")
			(hide yes)
			(effects
				(font
					(size 1.016 1.016)
					(thickness 0.1524)
				)
			)
		)
		(property "Device Type" "R402H16"
			(at 0.064008 -5.517896 0)
			(unlocked yes)
			(layer "F.Fab")
			(hide yes)
			(effects
				(font
					(size 1.016 1.016)
					(thickness 0.1524)
				)
			)
		)
		(duplicate_pad_numbers_are_jumpers no)
		(fp_line
			(start -0.508 -0.9398)
			(end -0.508 0.9398)
			(stroke
				(width 0.1524)
				(type default)
			)
			(layer "F.SilkS")
		)
		(fp_line
			(start 0.508 -0.9398)
			(end -0.508 -0.9398)
			(stroke
				(width 0.1524)
				(type default)
			)
			(layer "F.SilkS")
		)
		(fp_rect
			(start -0.508 0.9398)
			(end 0.508 -0.9398)
			(stroke
				(width 0)
				(type default)
			)
			(fill no)
			(layer "F.CrtYd")
		)
		(fp_rect
			(start -0.508 0.9398)
			(end 0.508 -0.9398)
			(stroke
				(width 0)
				(type default)
			)
			(fill no)
			(layer "F.Fab")
		)
		(pad "1" smd custom
			(at 0 -0.4445)
			(size 0.1397 0.1397)
			(layers "F.Cu" "F.Mask" "F.Paste")
			(net "GND")
			(options
				(clearance outline)
				(anchor circle)
			)
			(primitives
				(gr_poly
					(pts
						(arc
							(start -0.1778 -0.2794)
							(mid -0.249642 -0.249642)
							(end -0.2794 -0.1778)
						)
						(arc
							(start -0.2794 0.1778)
							(mid -0.249642 0.249642)
							(end -0.1778 0.2794)
						)
						(arc
							(start 0.1778 0.2794)
							(mid 0.249642 0.249642)
							(end 0.2794 0.1778)
						)
						(arc
							(start 0.2794 -0.1778)
							(mid 0.249642 -0.249642)
							(end 0.1778 -0.2794)
						)
					)
					(width 0)
					(fill yes)
				)
			)
		)
		(pad "2" smd custom
			(at 0 0.4445)
			(size 0.1397 0.1397)
			(layers "F.Cu" "F.Mask" "F.Paste")
			(net "TP_BMC0_LPC_LAD0")
			(options
				(clearance outline)
				(anchor circle)
			)
			(primitives
				(gr_poly
					(pts
						(arc
							(start -0.1778 -0.2794)
							(mid -0.249642 -0.249642)
							(end -0.2794 -0.1778)
						)
						(arc
							(start -0.2794 0.1778)
							(mid -0.249642 0.249642)
							(end -0.1778 0.2794)
						)
						(arc
							(start 0.1778 0.2794)
							(mid 0.249642 0.249642)
							(end 0.2794 0.1778)
						)
						(arc
							(start 0.2794 -0.1778)
							(mid 0.249642 -0.249642)
							(end 0.1778 -0.2794)
						)
					)
					(width 0)
					(fill yes)
				)
			)
		)
	)
)
